# T6G (Grand Teton) — schematic netlist excerpt (pin names and nets, part order shuffled) for the footprints in the layout excerpt that follows; sources: Cadence DE-HDL packaged netlist, KiCad conversion of 04192023_DAF0TMB3IC0_F0TG_MB_C_brd_V02_OCP.brd

C471  Q_CAP  100UF 4V 20% X6S  pkg C0805  page 356 : A = P0V9_CPU1_RT3_2A ; B = GND
PR332  Q_RES  0 5% CHIP  pkg 0402LF  page 225 : A = PVDD11_S3_P1_VOS1 ; B = PVDD11_S3_P1
R2837  Q_RES  100K 1% EMPTY  pkg 0402LF  page 127 : A = P3V3_AUX ; B = FM_SWB_PWRGD

(kicad_pcb
	(version 20260206)
	(generator "pcbnew")
	(generator_version "10.0")
	(general
		(thickness 1.6)
		(legacy_teardrops no)
	)
	(paper "A4")
	(title_block
		(title "04192023_DAF0TMB3IC0_F0TG_MB_C_brd_V02_OCP.brd")
		(comment 1 "Grand Teton / footprints 6193-6195 of 8354")
	)
	(layers
		(0 "F.Cu" signal "TOP")
		(4 "In1.Cu" signal "GND")
		(6 "In2.Cu" signal "IN1")
		(8 "In3.Cu" signal "GND1")
		(10 "In4.Cu" signal "IN2")
		(12 "In5.Cu" signal "GND2")
		(14 "In6.Cu" signal "IN3")
		(16 "In7.Cu" signal "GND3")
		(18 "In8.Cu" signal "VCC")
		(20 "In9.Cu" signal "VCC1")
		(22 "In10.Cu" signal "GND4")
		(24 "In11.Cu" signal "IN4")
		(26 "In12.Cu" signal "GND5")
		(28 "In13.Cu" signal "IN5")
		(30 "In14.Cu" signal "GND6")
		(32 "In15.Cu" signal "IN6")
		(34 "In16.Cu" signal "GND7")
		(2 "B.Cu" signal "BOTTOM")
		(9 "F.Adhes" user "F.Adhesive")
		(11 "B.Adhes" user "B.Adhesive")
		(13 "F.Paste" user "Package Geometry/Pastemask Top")
		(15 "B.Paste" user "Package Geometry/Pastemask Bottom")
		(5 "F.SilkS" user "Ref Des/Silkscreen Top")
		(7 "B.SilkS" user "Ref Des/Silkscreen Bottom")
		(1 "F.Mask" user "Board Geometry/Soldermask Top")
		(3 "B.Mask" user "Board Geometry/Soldermask Bottom")
		(17 "Dwgs.User" user "User.Drawings")
		(19 "Cmts.User" user "User.Comments")
		(21 "Eco1.User" user "User.Eco1")
		(23 "Eco2.User" user "User.Eco2")
		(25 "Edge.Cuts" user "Board Geometry/Outline")
		(27 "Margin" user)
		(31 "F.CrtYd" user "Package Geometry/Place Bound Top")
		(29 "B.CrtYd" user "Package Geometry/Place Bound Bottom")
		(35 "F.Fab" user "Ref Des/Assembly Top")
		(33 "B.Fab" user "Ref Des/Assembly Bottom")
	)
	(footprint ""
		(layer "B.Cu")
		(at 357.730806 -419.02888 180)
		(property "Reference" "R2837"
			(at 0 0 0)
			(layer "B.SilkS")
			(hide yes)
			(effects
				(font
					(size 1.27 1.27)
				)
				(justify mirror)
			)
		)
		(property "Value" ""
			(at 0 0 0)
			(layer "B.Fab")
			(effects
				(font
					(size 1.27 1.27)
				)
				(justify mirror)
			)
		)
		(duplicate_pad_numbers_are_jumpers no)
		(fp_line
			(start 0.7874 0.4064)
			(end 0.7874 -0.4064)
			(stroke
				(width 0.1524)
				(type default)
			)
			(layer "B.SilkS")
		)
		(fp_line
			(start 0.7874 -0.4064)
			(end -0.7874 -0.4064)
			(stroke
				(width 0.1524)
				(type default)
			)
			(layer "B.SilkS")
		)
		(fp_line
			(start -0.7874 0.4064)
			(end 0.7874 0.4064)
			(stroke
				(width 0.1524)
				(type default)
			)
			(layer "B.SilkS")
		)
		(fp_line
			(start -0.7874 -0.4064)
			(end -0.7874 0.4064)
			(stroke
				(width 0.1524)
				(type default)
			)
			(layer "B.SilkS")
		)
		(fp_line
			(start 0.67945 0.3048)
			(end 0.67945 -0.305054)
			(stroke
				(width 0.1)
				(type default)
			)
			(layer "B.Fab")
		)
		(fp_line
			(start 0.67945 -0.305054)
			(end 0.12065 -0.305054)
			(stroke
				(width 0.1)
				(type default)
			)
			(layer "B.Fab")
		)
		(fp_line
			(start 0.12065 0.3048)
			(end 0.67945 0.3048)
			(stroke
				(width 0.1)
				(type default)
			)
			(layer "B.Fab")
		)
		(fp_line
			(start 0.12065 0.2794)
			(end 0.12065 0.3048)
			(stroke
				(width 0.1)
				(type default)
			)
			(layer "B.Fab")
		)
		(fp_line
			(start 0.12065 -0.2794)
			(end -0.12065 -0.2794)
			(stroke
				(width 0.1)
				(type default)
			)
			(layer "B.Fab")
		)
		(fp_line
			(start 0.12065 -0.305054)
			(end 0.12065 -0.2794)
			(stroke
				(width 0.1)
				(type default)
			)
			(layer "B.Fab")
		)
		(fp_line
			(start -0.120396 0.3048)
			(end -0.120396 0.2794)
			(stroke
				(width 0.1)
				(type default)
			)
			(layer "B.Fab")
		)
		(fp_line
			(start -0.120396 0.2794)
			(end 0.12065 0.2794)
			(stroke
				(width 0.1)
				(type default)
			)
			(layer "B.Fab")
		)
		(fp_line
			(start -0.12065 -0.2794)
			(end -0.12065 -0.3048)
			(stroke
				(width 0.1)
				(type default)
			)
			(layer "B.Fab")
		)
		(fp_line
			(start -0.12065 -0.3048)
			(end -0.67945 -0.3048)
			(stroke
				(width 0.1)
				(type default)
			)
			(layer "B.Fab")
		)
		(fp_line
			(start -0.67945 0.3048)
			(end -0.120396 0.3048)
			(stroke
				(width 0.1)
				(type default)
			)
			(layer "B.Fab")
		)
		(fp_line
			(start -0.67945 -0.3048)
			(end -0.67945 0.3048)
			(stroke
				(width 0.1)
				(type default)
			)
			(layer "B.Fab")
		)
		(pad "1" smd circle
			(at 0.40005 0)
			(size 0 0)
			(layers "B.Cu" "B.Mask" "B.Paste")
			(net "P3V3_AUX")
		)
		(pad "2" smd circle
			(at -0.40005 0)
			(size 0 0)
			(layers "B.Cu" "B.Mask" "B.Paste")
			(net "FM_SWB_PWRGD")
		)
	)
	(footprint ""
		(layer "B.Cu")
		(at 136.936226 -391.81405 180)
		(property "Reference" "C471"
			(at 0 0 0)
			(layer "B.SilkS")
			(hide yes)
			(effects
				(font
					(size 1.27 1.27)
				)
				(justify mirror)
			)
		)
		(property "Value" ""
			(at 0 0 0)
			(layer "B.Fab")
			(effects
				(font
					(size 1.27 1.27)
				)
				(justify mirror)
			)
		)
		(duplicate_pad_numbers_are_jumpers no)
		(fp_line
			(start 1.524 0.762)
			(end 1.524 -0.762)
			(stroke
				(width 0.1524)
				(type default)
			)
			(layer "B.SilkS")
		)
		(fp_line
			(start 1.524 -0.762)
			(end -1.524 -0.762)
			(stroke
				(width 0.1524)
				(type default)
			)
			(layer "B.SilkS")
		)
		(fp_line
			(start -1.524 0.762)
			(end 1.524 0.762)
			(stroke
				(width 0.1524)
				(type default)
			)
			(layer "B.SilkS")
		)
		(fp_line
			(start -1.524 -0.762)
			(end -1.524 0.762)
			(stroke
				(width 0.1524)
				(type default)
			)
			(layer "B.SilkS")
		)
		(fp_line
			(start 1.1049 0.724916)
			(end -1.1049 0.724916)
			(stroke
				(width 0.1)
				(type default)
			)
			(layer "B.Fab")
		)
		(fp_line
			(start 1.1049 -0.724916)
			(end 1.1049 0.724916)
			(stroke
				(width 0.1)
				(type default)
			)
			(layer "B.Fab")
		)
		(fp_line
			(start -1.1049 0.724916)
			(end -1.1049 -0.724916)
			(stroke
				(width 0.1)
				(type default)
			)
			(layer "B.Fab")
		)
		(fp_line
			(start -1.1049 -0.724916)
			(end 1.1049 -0.724916)
			(stroke
				(width 0.1)
				(type default)
			)
			(layer "B.Fab")
		)
		(pad "1" smd rect
			(at 0.889 0 180)
			(size 1.016 1.27)
			(layers "B.Cu" "B.Mask" "B.Paste")
			(net "P0V9_CPU1_RT3_2A")
		)
		(pad "2" smd rect
			(at -0.889 0 180)
			(size 1.016 1.27)
			(layers "B.Cu" "B.Mask" "B.Paste")
			(net "GND")
		)
	)
	(footprint ""
		(layer "B.Cu")
		(at 179.258468 -353.960684 -90)
		(property "Reference" "PR332"
			(at 0 0 90)
			(layer "B.SilkS")
			(hide yes)
			(effects
				(font
					(size 1.27 1.27)
				)
				(justify mirror)
			)
		)
		(property "Value" ""
			(at 0 0 90)
			(layer "B.Fab")
			(effects
				(font
					(size 1.27 1.27)
				)
				(justify mirror)
			)
		)
		(duplicate_pad_numbers_are_jumpers no)
		(fp_line
			(start -0.7874 0.4064)
			(end 0.7874 0.4064)
			(stroke
				(width 0.1524)
				(type default)
			)
			(layer "B.SilkS")
		)
		(fp_line
			(start 0.7874 0.4064)
			(end 0.7874 -0.4064)
			(stroke
				(width 0.1524)
				(type default)
			)
			(layer "B.SilkS")
		)
		(fp_line
			(start -0.7874 -0.4064)
			(end -0.7874 0.4064)
			(stroke
				(width 0.1524)
				(type default)
			)
			(layer "B.SilkS")
		)
		(fp_line
			(start 0.7874 -0.4064)
			(end -0.7874 -0.4064)
			(stroke
				(width 0.1524)
				(type default)
			)
			(layer "B.SilkS")
		)
		(fp_line
			(start -0.67945 0.3048)
			(end -0.120396 0.3048)
			(stroke
				(width 0.1)
				(type default)
			)
			(layer "B.Fab")
		)
		(fp_line
			(start -0.120396 0.3048)
			(end -0.120396 0.2794)
			(stroke
				(width 0.1)
				(type default)
			)
			(layer "B.Fab")
		)
		(fp_line
			(start 0.12065 0.3048)
			(end 0.67945 0.3048)
			(stroke
				(width 0.1)
				(type default)
			)
			(layer "B.Fab")
		)
		(fp_line
			(start 0.67945 0.3048)
			(end 0.67945 -0.305054)
			(stroke
				(width 0.1)
				(type default)
			)
			(layer "B.Fab")
		)
		(fp_line
			(start -0.120396 0.2794)
			(end 0.12065 0.2794)
			(stroke
				(width 0.1)
				(type default)
			)
			(layer "B.Fab")
		)
		(fp_line
			(start 0.12065 0.2794)
			(end 0.12065 0.3048)
			(stroke
				(width 0.1)
				(type default)
			)
			(layer "B.Fab")
		)
		(fp_line
			(start -0.12065 -0.2794)
			(end -0.12065 -0.3048)
			(stroke
				(width 0.1)
				(type default)
			)
			(layer "B.Fab")
		)
		(fp_line
			(start 0.12065 -0.2794)
			(end -0.12065 -0.2794)
			(stroke
				(width 0.1)
				(type default)
			)
			(layer "B.Fab")
		)
		(fp_line
			(start -0.67945 -0.3048)
			(end -0.67945 0.3048)
			(stroke
				(width 0.1)
				(type default)
			)
			(layer "B.Fab")
		)
		(fp_line
			(start -0.12065 -0.3048)
			(end -0.67945 -0.3048)
			(stroke
				(width 0.1)
				(type default)
			)
			(layer "B.Fab")
		)
		(fp_line
			(start 0.12065 -0.305054)
			(end 0.12065 -0.2794)
			(stroke
				(width 0.1)
				(type default)
			)
			(layer "B.Fab")
		)
		(fp_line
			(start 0.67945 -0.305054)
			(end 0.12065 -0.305054)
			(stroke
				(width 0.1)
				(type default)
			)
			(layer "B.Fab")
		)
		(pad "1" smd circle
			(at 0.40005 0 90)
			(size 0 0)
			(layers "B.Cu" "B.Mask" "B.Paste")
			(net "PVDD11_S3_P1_VOS1")
		)
		(pad "2" smd circle
			(at -0.40005 0 90)
			(size 0 0)
			(layers "B.Cu" "B.Mask" "B.Paste")
			(net "PVDD11_S3_P1")
		)
	)
)
